(kicad_pcb
	(version 20260206)
	(generator "pcbnew")
	(generator_version "10.0")
	(general
		(thickness 1.6)
		(legacy_teardrops no)
	)
	(paper "A4")
	(title_block
		(title "01162023_DA0F0TEBIF0_F0T_Expander_BD_F_brd_V02_OCP.brd")
		(comment 1 "Grand Teton / footprints 1404-1411 of 9728")
	)
	(layers
		(0 "F.Cu" signal "TOP")
		(4 "In1.Cu" signal "GND")
		(6 "In2.Cu" signal "VCC")
		(8 "In3.Cu" signal "VCC1")
		(10 "In4.Cu" signal "GND1")
		(12 "In5.Cu" signal "IN1")
		(14 "In6.Cu" signal "GND2")
		(16 "In7.Cu" signal "IN2")
		(18 "In8.Cu" signal "GND3")
		(20 "In9.Cu" signal "IN3")
		(22 "In10.Cu" signal "GND4")
		(24 "In11.Cu" signal "IN4")
		(26 "In12.Cu" signal "GND5")
		(28 "In13.Cu" signal "IN5")
		(30 "In14.Cu" signal "GND6")
		(32 "In15.Cu" signal "IN6")
		(34 "In16.Cu" signal "GND7")
		(2 "B.Cu" signal "BOTTOM")
		(9 "F.Adhes" user "F.Adhesive")
		(11 "B.Adhes" user "B.Adhesive")
		(13 "F.Paste" user "Package Geometry/Pastemask Top")
		(15 "B.Paste" user "Package Geometry/Pastemask Bottom")
		(5 "F.SilkS" user "Ref Des/Silkscreen Top")
		(7 "B.SilkS" user "Ref Des/Silkscreen Bottom")
		(1 "F.Mask" user "Board Geometry/Soldermask Top")
		(3 "B.Mask" user "Board Geometry/Soldermask Bottom")
		(17 "Dwgs.User" user "User.Drawings")
		(19 "Cmts.User" user "User.Comments")
		(21 "Eco1.User" user "User.Eco1")
		(23 "Eco2.User" user "User.Eco2")
		(25 "Edge.Cuts" user "Board Geometry/Outline")
		(27 "Margin" user)
		(31 "F.CrtYd" user "Package Geometry/Place Bound Top")
		(29 "B.CrtYd" user "Package Geometry/Place Bound Bottom")
		(35 "F.Fab" user "Ref Des/Assembly Top")
		(33 "B.Fab" user "Ref Des/Assembly Bottom")
	)
	(footprint ""
		(layer "F.Cu")
		(at 18.722594 -44.341542 90)
		(property "Reference" "R514"
			(at 0 0 90)
			(layer "F.SilkS")
			(hide yes)
			(effects
				(font
					(size 1.27 1.27)
				)
			)
		)
		(property "Value" ""
			(at 0 0 90)
			(layer "F.Fab")
			(effects
				(font
					(size 1.27 1.27)
				)
			)
		)
		(duplicate_pad_numbers_are_jumpers no)
		(fp_line
			(start 0.7874 -0.4064)
			(end 0.7874 0.4064)
			(stroke
				(width 0.1524)
				(type default)
			)
			(layer "F.SilkS")
		)
		(fp_line
			(start -0.7874 -0.4064)
			(end 0.7874 -0.4064)
			(stroke
				(width 0.1524)
				(type default)
			)
			(layer "F.SilkS")
		)
		(fp_line
			(start 0.7874 0.4064)
			(end -0.7874 0.4064)
			(stroke
				(width 0.1524)
				(type default)
			)
			(layer "F.SilkS")
		)
		(fp_line
			(start -0.7874 0.4064)
			(end -0.7874 -0.4064)
			(stroke
				(width 0.1524)
				(type default)
			)
			(layer "F.SilkS")
		)
		(fp_line
			(start -0.12065 -0.305054)
			(end -0.12065 -0.2794)
			(stroke
				(width 0.1)
				(type default)
			)
			(layer "F.Fab")
		)
		(fp_line
			(start -0.67945 -0.305054)
			(end -0.12065 -0.305054)
			(stroke
				(width 0.1)
				(type default)
			)
			(layer "F.Fab")
		)
		(fp_line
			(start 0.67945 -0.3048)
			(end 0.67945 0.3048)
			(stroke
				(width 0.1)
				(type default)
			)
			(layer "F.Fab")
		)
		(fp_line
			(start 0.12065 -0.3048)
			(end 0.67945 -0.3048)
			(stroke
				(width 0.1)
				(type default)
			)
			(layer "F.Fab")
		)
		(fp_line
			(start 0.12065 -0.2794)
			(end 0.12065 -0.3048)
			(stroke
				(width 0.1)
				(type default)
			)
			(layer "F.Fab")
		)
		(fp_line
			(start -0.12065 -0.2794)
			(end 0.12065 -0.2794)
			(stroke
				(width 0.1)
				(type default)
			)
			(layer "F.Fab")
		)
		(fp_line
			(start 0.120396 0.2794)
			(end -0.12065 0.2794)
			(stroke
				(width 0.1)
				(type default)
			)
			(layer "F.Fab")
		)
		(fp_line
			(start -0.12065 0.2794)
			(end -0.12065 0.3048)
			(stroke
				(width 0.1)
				(type default)
			)
			(layer "F.Fab")
		)
		(fp_line
			(start 0.67945 0.3048)
			(end 0.120396 0.3048)
			(stroke
				(width 0.1)
				(type default)
			)
			(layer "F.Fab")
		)
		(fp_line
			(start 0.120396 0.3048)
			(end 0.120396 0.2794)
			(stroke
				(width 0.1)
				(type default)
			)
			(layer "F.Fab")
		)
		(fp_line
			(start -0.12065 0.3048)
			(end -0.67945 0.3048)
			(stroke
				(width 0.1)
				(type default)
			)
			(layer "F.Fab")
		)
		(fp_line
			(start -0.67945 0.3048)
			(end -0.67945 -0.305054)
			(stroke
				(width 0.1)
				(type default)
			)
			(layer "F.Fab")
		)
		(pad "1" smd circle
			(at -0.40005 0 90)
			(size 0 0)
			(layers "F.Cu" "F.Mask" "F.Paste")
			(net "P12V_SSD0")
		)
		(pad "2" smd circle
			(at 0.40005 0 90)
			(size 0 0)
			(layers "F.Cu" "F.Mask" "F.Paste")
			(net "P12V_SSD0_VIN_N")
		)
	)
	(footprint ""
		(layer "F.Cu")
		(at 479.221546 -554.52518 180)
		(property "Reference" "J56_12"
			(at -2.8448 -1.402334 0)
			(unlocked yes)
			(layer "B.SilkS")
			(effects
				(font
					(size 0.7874 0.5842)
					(thickness 0.1524)
				)
				(justify mirror)
			)
		)
		(property "Value" ""
			(at 0 0 180)
			(layer "F.Fab")
			(effects
				(font
					(size 1.27 1.27)
				)
			)
		)
		(duplicate_pad_numbers_are_jumpers no)
		(pad "1" thru_hole circle
			(at 0 0 180)
			(size 0.4572 0.4572)
			(drill 0.2032)
			(layers "*.Cu" "*.Mask")
			(remove_unused_layers no)
			(net "Net_2679")
			(clearance 0.127)
			(thermal_gap 0.127)
			(padstack
				(mode front_inner_back)
				(layer "Inner"
					(shape circle)
					(size 0.4572 0.4572)
					(clearance 0.127)
				)
				(layer "B.Cu"
					(shape circle)
					(size 0.508 0.508)
					(clearance 0.1016)
				)
			)
		)
	)
	(footprint ""
		(layer "F.Cu")
		(at 224.022158 -86.700868)
		(property "Reference" "R4264"
			(at 0 0 0)
			(layer "F.SilkS")
			(hide yes)
			(effects
				(font
					(size 1.27 1.27)
				)
			)
		)
		(property "Value" ""
			(at 0 0 0)
			(layer "F.Fab")
			(effects
				(font
					(size 1.27 1.27)
				)
			)
		)
		(duplicate_pad_numbers_are_jumpers no)
		(fp_line
			(start -0.7874 -0.4064)
			(end 0.7874 -0.4064)
			(stroke
				(width 0.1524)
				(type default)
			)
			(layer "F.SilkS")
		)
		(fp_line
			(start -0.7874 0.4064)
			(end -0.7874 -0.4064)
			(stroke
				(width 0.1524)
				(type default)
			)
			(layer "F.SilkS")
		)
		(fp_line
			(start 0.7874 -0.4064)
			(end 0.7874 0.4064)
			(stroke
				(width 0.1524)
				(type default)
			)
			(layer "F.SilkS")
		)
		(fp_line
			(start 0.7874 0.4064)
			(end -0.7874 0.4064)
			(stroke
				(width 0.1524)
				(type default)
			)
			(layer "F.SilkS")
		)
		(fp_line
			(start -0.67945 -0.305054)
			(end -0.12065 -0.305054)
			(stroke
				(width 0.1)
				(type default)
			)
			(layer "F.Fab")
		)
		(fp_line
			(start -0.67945 0.3048)
			(end -0.67945 -0.305054)
			(stroke
				(width 0.1)
				(type default)
			)
			(layer "F.Fab")
		)
		(fp_line
			(start -0.12065 -0.305054)
			(end -0.12065 -0.2794)
			(stroke
				(width 0.1)
				(type default)
			)
			(layer "F.Fab")
		)
		(fp_line
			(start -0.12065 -0.2794)
			(end 0.12065 -0.2794)
			(stroke
				(width 0.1)
				(type default)
			)
			(layer "F.Fab")
		)
		(fp_line
			(start -0.12065 0.2794)
			(end -0.12065 0.3048)
			(stroke
				(width 0.1)
				(type default)
			)
			(layer "F.Fab")
		)
		(fp_line
			(start -0.12065 0.3048)
			(end -0.67945 0.3048)
			(stroke
				(width 0.1)
				(type default)
			)
			(layer "F.Fab")
		)
		(fp_line
			(start 0.120396 0.2794)
			(end -0.12065 0.2794)
			(stroke
				(width 0.1)
				(type default)
			)
			(layer "F.Fab")
		)
		(fp_line
			(start 0.120396 0.3048)
			(end 0.120396 0.2794)
			(stroke
				(width 0.1)
				(type default)
			)
			(layer "F.Fab")
		)
		(fp_line
			(start 0.12065 -0.3048)
			(end 0.67945 -0.3048)
			(stroke
				(width 0.1)
				(type default)
			)
			(layer "F.Fab")
		)
		(fp_line
			(start 0.12065 -0.2794)
			(end 0.12065 -0.3048)
			(stroke
				(width 0.1)
				(type default)
			)
			(layer "F.Fab")
		)
		(fp_line
			(start 0.67945 -0.3048)
			(end 0.67945 0.3048)
			(stroke
				(width 0.1)
				(type default)
			)
			(layer "F.Fab")
		)
		(fp_line
			(start 0.67945 0.3048)
			(end 0.120396 0.3048)
			(stroke
				(width 0.1)
				(type default)
			)
			(layer "F.Fab")
		)
		(pad "1" smd circle
			(at -0.40005 0)
			(size 0 0)
			(layers "F.Cu" "F.Mask" "F.Paste")
			(net "SMB_SSD_LED_IOEXP_SCL")
		)
		(pad "2" smd circle
			(at 0.40005 0)
			(size 0 0)
			(layers "F.Cu" "F.Mask" "F.Paste")
			(net "SMB_BIC_I2C6_R_SCL")
		)
	)
	(footprint ""
		(layer "F.Cu")
		(at 444.09233 -29.139642 180)
		(property "Reference" "C728"
			(at 0 0 180)
			(layer "F.SilkS")
			(hide yes)
			(effects
				(font
					(size 1.27 1.27)
				)
			)
		)
		(property "Value" ""
			(at 0 0 180)
			(layer "F.Fab")
			(effects
				(font
					(size 1.27 1.27)
				)
			)
		)
		(duplicate_pad_numbers_are_jumpers no)
		(fp_line
			(start 0.299974 0.150114)
			(end -0.299974 0.150114)
			(stroke
				(width 0.1)
				(type default)
			)
			(layer "F.Fab")
		)
		(fp_line
			(start 0.299974 -0.150114)
			(end 0.299974 0.150114)
			(stroke
				(width 0.1)
				(type default)
			)
			(layer "F.Fab")
		)
		(fp_line
			(start -0.299974 0.150114)
			(end -0.299974 -0.150114)
			(stroke
				(width 0.1)
				(type default)
			)
			(layer "F.Fab")
		)
		(fp_line
			(start -0.299974 -0.150114)
			(end 0.299974 -0.150114)
			(stroke
				(width 0.1)
				(type default)
			)
			(layer "F.Fab")
		)
		(pad "1" smd rect
			(at -0.2667 0 180)
			(size 0.3048 0.381)
			(layers "F.Cu" "F.Mask" "F.Paste")
			(net "P5E_PEX3_STN2_TX_DP<32>")
		)
		(pad "2" smd rect
			(at 0.2667 0 180)
			(size 0.3048 0.381)
			(layers "F.Cu" "F.Mask" "F.Paste")
			(net "P5E_PEX3_STN2_TX_C_DP<32>")
		)
	)
	(footprint ""
		(layer "F.Cu")
		(at 335.367884 -114.833654 90)
		(property "Reference" "PR7030"
			(at 0 0 90)
			(layer "F.SilkS")
			(hide yes)
			(effects
				(font
					(size 1.27 1.27)
				)
			)
		)
		(property "Value" ""
			(at 0 0 90)
			(layer "F.Fab")
			(effects
				(font
					(size 1.27 1.27)
				)
			)
		)
		(duplicate_pad_numbers_are_jumpers no)
		(fp_line
			(start 1.2954 -0.5842)
			(end 1.2954 0.5842)
			(stroke
				(width 0.1524)
				(type default)
			)
			(layer "F.SilkS")
		)
		(fp_line
			(start -1.2954 -0.5842)
			(end 1.2954 -0.5842)
			(stroke
				(width 0.1524)
				(type default)
			)
			(layer "F.SilkS")
		)
		(fp_line
			(start 1.2954 0.5842)
			(end -1.2954 0.5842)
			(stroke
				(width 0.1524)
				(type default)
			)
			(layer "F.SilkS")
		)
		(fp_line
			(start -1.2954 0.5842)
			(end -1.2954 -0.5842)
			(stroke
				(width 0.1524)
				(type default)
			)
			(layer "F.SilkS")
		)
		(fp_line
			(start 0.8636 -0.4572)
			(end 0.8636 -0.406654)
			(stroke
				(width 0.1)
				(type default)
			)
			(layer "F.Fab")
		)
		(fp_line
			(start -0.8636 -0.4572)
			(end 0.8636 -0.4572)
			(stroke
				(width 0.1)
				(type default)
			)
			(layer "F.Fab")
		)
		(fp_line
			(start 1.1938 -0.406654)
			(end 1.1938 0.4064)
			(stroke
				(width 0.1)
				(type default)
			)
			(layer "F.Fab")
		)
		(fp_line
			(start 0.8636 -0.406654)
			(end 1.1938 -0.406654)
			(stroke
				(width 0.1)
				(type default)
			)
			(layer "F.Fab")
		)
		(fp_line
			(start -0.8636 -0.406654)
			(end -0.8636 -0.4572)
			(stroke
				(width 0.1)
				(type default)
			)
			(layer "F.Fab")
		)
		(fp_line
			(start -1.1938 -0.406654)
			(end -0.8636 -0.406654)
			(stroke
				(width 0.1)
				(type default)
			)
			(layer "F.Fab")
		)
		(fp_line
			(start 1.1938 0.4064)
			(end 0.8636 0.4064)
			(stroke
				(width 0.1)
				(type default)
			)
			(layer "F.Fab")
		)
		(fp_line
			(start 0.8636 0.4064)
			(end 0.8636 0.4572)
			(stroke
				(width 0.1)
				(type default)
			)
			(layer "F.Fab")
		)
		(fp_line
			(start -0.8636 0.4064)
			(end -1.1938 0.4064)
			(stroke
				(width 0.1)
				(type default)
			)
			(layer "F.Fab")
		)
		(fp_line
			(start -1.1938 0.4064)
			(end -1.1938 -0.406654)
			(stroke
				(width 0.1)
				(type default)
			)
			(layer "F.Fab")
		)
		(fp_line
			(start -0.8636 0.4318)
			(end -0.8636 0.4064)
			(stroke
				(width 0.1)
				(type default)
			)
			(layer "F.Fab")
		)
		(fp_line
			(start 0.8636 0.4572)
			(end -0.8636 0.4572)
			(stroke
				(width 0.1)
				(type default)
			)
			(layer "F.Fab")
		)
		(fp_line
			(start -0.8636 0.4572)
			(end -0.8636 0.4318)
			(stroke
				(width 0.1)
				(type default)
			)
			(layer "F.Fab")
		)
		(pad "1" smd rect
			(at -0.7366 0)
			(size 0.7112 0.8128)
			(layers "F.Cu" "F.Mask" "F.Paste")
			(net "P12V_NIC5_CO_AVIN_PD")
		)
		(pad "2" smd rect
			(at 0.7366 0)
			(size 0.7112 0.8128)
			(layers "F.Cu" "F.Mask" "F.Paste")
			(net "P12V_AUX")
		)
	)
	(footprint ""
		(layer "F.Cu")
		(at 31.650178 -50.96383 180)
		(property "Reference" "PC513"
			(at 0 0 180)
			(layer "F.SilkS")
			(hide yes)
			(effects
				(font
					(size 1.27 1.27)
				)
			)
		)
		(property "Value" ""
			(at 0 0 180)
			(layer "F.Fab")
			(effects
				(font
					(size 1.27 1.27)
				)
			)
		)
		(duplicate_pad_numbers_are_jumpers no)
		(fp_line
			(start 1.524 0.762)
			(end -1.524 0.762)
			(stroke
				(width 0.1524)
				(type default)
			)
			(layer "F.SilkS")
		)
		(fp_line
			(start 1.524 -0.762)
			(end 1.524 0.762)
			(stroke
				(width 0.1524)
				(type default)
			)
			(layer "F.SilkS")
		)
		(fp_line
			(start -1.524 0.762)
			(end -1.524 -0.762)
			(stroke
				(width 0.1524)
				(type default)
			)
			(layer "F.SilkS")
		)
		(fp_line
			(start -1.524 -0.762)
			(end 1.524 -0.762)
			(stroke
				(width 0.1524)
				(type default)
			)
			(layer "F.SilkS")
		)
		(fp_line
			(start 1.1049 0.724916)
			(end 1.1049 -0.724916)
			(stroke
				(width 0.1)
				(type default)
			)
			(layer "F.Fab")
		)
		(fp_line
			(start 1.1049 -0.724916)
			(end -1.1049 -0.724916)
			(stroke
				(width 0.1)
				(type default)
			)
			(layer "F.Fab")
		)
		(fp_line
			(start -1.1049 0.724916)
			(end 1.1049 0.724916)
			(stroke
				(width 0.1)
				(type default)
			)
			(layer "F.Fab")
		)
		(fp_line
			(start -1.1049 -0.724916)
			(end -1.1049 0.724916)
			(stroke
				(width 0.1)
				(type default)
			)
			(layer "F.Fab")
		)
		(pad "1" smd rect
			(at -0.889 0)
			(size 1.016 1.27)
			(layers "F.Cu" "F.Mask" "F.Paste")
			(net "P3V3_SSD1")
		)
		(pad "2" smd rect
			(at 0.889 0)
			(size 1.016 1.27)
			(layers "F.Cu" "F.Mask" "F.Paste")
			(net "GND")
		)
	)
	(footprint ""
		(layer "F.Cu")
		(at 188.534548 -30.03169 180)
		(property "Reference" "C297"
			(at 0 0 180)
			(layer "F.SilkS")
			(hide yes)
			(effects
				(font
					(size 1.27 1.27)
				)
			)
		)
		(property "Value" ""
			(at 0 0 180)
			(layer "F.Fab")
			(effects
				(font
					(size 1.27 1.27)
				)
			)
		)
		(duplicate_pad_numbers_are_jumpers no)
		(fp_line
			(start 0.299974 0.150114)
			(end -0.299974 0.150114)
			(stroke
				(width 0.1)
				(type default)
			)
			(layer "F.Fab")
		)
		(fp_line
			(start 0.299974 -0.150114)
			(end 0.299974 0.150114)
			(stroke
				(width 0.1)
				(type default)
			)
			(layer "F.Fab")
		)
		(fp_line
			(start -0.299974 0.150114)
			(end -0.299974 -0.150114)
			(stroke
				(width 0.1)
				(type default)
			)
			(layer "F.Fab")
		)
		(fp_line
			(start -0.299974 -0.150114)
			(end 0.299974 -0.150114)
			(stroke
				(width 0.1)
				(type default)
			)
			(layer "F.Fab")
		)
		(pad "1" smd rect
			(at -0.2667 0 180)
			(size 0.3048 0.381)
			(layers "F.Cu" "F.Mask" "F.Paste")
			(net "P5E_PEX1_STN2_TX_DN<37>")
		)
		(pad "2" smd rect
			(at 0.2667 0 180)
			(size 0.3048 0.381)
			(layers "F.Cu" "F.Mask" "F.Paste")
			(net "P5E_PEX1_STN2_TX_C_DN<37>")
		)
	)
	(footprint ""
		(layer "F.Cu")
		(at 259.326126 -39.73576 -90)
		(property "Reference" "R5569"
			(at 0 0 270)
			(layer "F.SilkS")
			(hide yes)
			(effects
				(font
					(size 1.27 1.27)
				)
			)
		)
		(property "Value" ""
			(at 0 0 270)
			(layer "F.Fab")
			(effects
				(font
					(size 1.27 1.27)
				)
			)
		)
		(duplicate_pad_numbers_are_jumpers no)
		(fp_line
			(start -0.7874 0.4064)
			(end -0.7874 -0.4064)
			(stroke
				(width 0.1524)
				(type default)
			)
			(layer "F.SilkS")
		)
		(fp_line
			(start 0.7874 0.4064)
			(end -0.7874 0.4064)
			(stroke
				(width 0.1524)
				(type default)
			)
			(layer "F.SilkS")
		)
		(fp_line
			(start -0.7874 -0.4064)
			(end 0.7874 -0.4064)
			(stroke
				(width 0.1524)
				(type default)
			)
			(layer "F.SilkS")
		)
		(fp_line
			(start 0.7874 -0.4064)
			(end 0.7874 0.4064)
			(stroke
				(width 0.1524)
				(type default)
			)
			(layer "F.SilkS")
		)
		(fp_line
			(start -0.67945 0.3048)
			(end -0.67945 -0.305054)
			(stroke
				(width 0.1)
				(type default)
			)
			(layer "F.Fab")
		)
		(fp_line
			(start -0.12065 0.3048)
			(end -0.67945 0.3048)
			(stroke
				(width 0.1)
				(type default)
			)
			(layer "F.Fab")
		)
		(fp_line
			(start 0.120396 0.3048)
			(end 0.120396 0.2794)
			(stroke
				(width 0.1)
				(type default)
			)
			(layer "F.Fab")
		)
		(fp_line
			(start 0.67945 0.3048)
			(end 0.120396 0.3048)
			(stroke
				(width 0.1)
				(type default)
			)
			(layer "F.Fab")
		)
		(fp_line
			(start -0.12065 0.2794)
			(end -0.12065 0.3048)
			(stroke
				(width 0.1)
				(type default)
			)
			(layer "F.Fab")
		)
		(fp_line
			(start 0.120396 0.2794)
			(end -0.12065 0.2794)
			(stroke
				(width 0.1)
				(type default)
			)
			(layer "F.Fab")
		)
		(fp_line
			(start -0.12065 -0.2794)
			(end 0.12065 -0.2794)
			(stroke
				(width 0.1)
				(type default)
			)
			(layer "F.Fab")
		)
		(fp_line
			(start 0.12065 -0.2794)
			(end 0.12065 -0.3048)
			(stroke
				(width 0.1)
				(type default)
			)
			(layer "F.Fab")
		)
		(fp_line
			(start 0.12065 -0.3048)
			(end 0.67945 -0.3048)
			(stroke
				(width 0.1)
				(type default)
			)
			(layer "F.Fab")
		)
		(fp_line
			(start 0.67945 -0.3048)
			(end 0.67945 0.3048)
			(stroke
				(width 0.1)
				(type default)
			)
			(layer "F.Fab")
		)
		(fp_line
			(start -0.67945 -0.305054)
			(end -0.12065 -0.305054)
			(stroke
				(width 0.1)
				(type default)
			)
			(layer "F.Fab")
		)
		(fp_line
			(start -0.12065 -0.305054)
			(end -0.12065 -0.2794)
			(stroke
				(width 0.1)
				(type default)
			)
			(layer "F.Fab")
		)
		(pad "1" smd circle
			(at -0.40005 0 270)
			(size 0 0)
			(layers "F.Cu" "F.Mask" "F.Paste")
			(net "P3V3_AUX")
		)
		(pad "2" smd circle
			(at 0.40005 0 270)
			(size 0 0)
			(layers "F.Cu" "F.Mask" "F.Paste")
			(net "SSD9_AUX_P3V3_EN")
		)
	)
)
